FILE_TYPE = CONNECTIVITY;
{Allegro Design Entry HDL 16.6-p007 (v16-6-112F) 10/10/2012}
"PAGE_NUMBER" = 191;
0"NC";
1"P3V3_STBY\g";
2"P3V3_STBY\g";
3"P3V3_STBY\g";
4"PWRGD_PCH_PWROK";
5"PU_RST_PERST_BIT1";
6"JTAG_PLD_TMS";
7"RST_PLTRST_N";
8"FM_PVDDQ_GHJ_EN";
9"FM_ADR_COMPLETE_DLY";
10"FM_FAST_PROCHOT_THROTTLE_IN_N";
11"TP_CPLD1_PT22C";
12"FM_UV_ADR_TRIGGER_N";
13"FM_CPU0_MCP_CLK_EN_N";
14"FM_PVCCIN_PVCCSA_CPU0_EN_LVC1";
15"FM_P1V8MCP_CPU1_EN";
16"PWRGD_P1V15_BMC_STBY";
17"PWRGD_P12V_MAIN";
18"FM_CTNR_PS_ON";
19"PWRGD_PVTT_CPU0";
20"FM_FORCE_ADR_N";
21"FM_SLP_SUS_N";
22"FM_PS_EN";
23"PU_CPLD1_PT20D_PROGRAMN";
24"SGPIO_BMC_DIN_R";
25"RST_PCIE_MIDPLANE_N";
26"SMB_SENSOR_STBY_LVC3_SCL";
27"SMB_SENSOR_STBY_LVC3_SDA";
28"PWRGD_SYS_PWROK";
29"FM_DB1200_PWRGD";
30"PWRGD_P1V8MCP_CPU1";
31"FM_CPLD_ADR_TRIGGER_N";
32"PWRGD_P1V8MCP_CPU0";
33"FM_P1V8MCP_CPU0_EN";
34"FM_CPU0_THERMTRIP_LATCH_LVT3_N";
35"PWRGD_CPUPWRGD";
36"FM_CPU1_THERMTRIP_LVT3_N";
37"FM_UV_ADR_TRIGGER_EN";
38"FM_PVDDQ_KLM_EN";
39"RST_BMC_SYSRST_BTN_OUT_B_R1_N";
40"RST_BMC_SYSRST_BTN_OUT_B_N";
41"PU_FAB2_MARKER_CPLD";
42"FM_P3V3_CPLD_EN";
43"FM_CPU1_THERMTRIP_LATCH_LVT3_N";
44"TP_CPLD1_PT11B";
45"FM_PCH_PRSNT_N";
46"RST_PCIE_CPU_DEV0_N";
47"JTAG_PLD_TDO";
48"JTAG_PLD_TDI";
49"FM_ADR_SMI_GPIO_R_N";
50"FM_CPU1_FIVR_FAULT_LVT3";
51"FM_CPU1_MCP_CLK_EN_N";
52"FM_WBG_PRSNT_N";
53"FM_CPU1_CD_PRES_N";
54"FM_CPU0_CD_PRES";
55"FM_CPU0_OR_CPU1_MCP_PRES";
56"FM_JTAG_PLD_EN_DEBUG";
57"FM_PCH_PWRBTN_R1_N";
58"TP_CPLD1_PT22D";
59"TP_CPLD1_PT20B";
60"TP_CPLD1_PT20A";
61"TP_CPLD1_PT19D";
62"FM_MEM_THERM_EVENT_LVT3_N";
63"TP_CPLD1_PT16B";
64"TP_CPLD1_PT17B_PCLKC0_1";
65"TP_CPLD1_PT17C";
66"TP_CPLD1_PR7A_PCLKT1_0";
67"TP_CPLD1_PR7B_PCLKC1_0";
68"TP_CPLD1_PR7C";
69"TP_CPLD1_PR7D";
70"TP_CPLD1_PR9A";
71"TP_CPLD1_PR9C";
72"TP_CPLD1_PR9D";
73"TP_CPLD1_PR10C";
74"TP_CPLD1_PR11B";
75"TP_CPLD1_PR12D";
76"FM_CPU1_PROC_ID0";
77"FM_THERMTRIP_DLY";
78"RST_PLTRST_BUF_N";
79"FM_CPU0_FIVR_FAULT_LVT3";
80"FM_CPU1_PROC_ID1";
81"FM_P12V_MAIN_SW_EN";
82"FM_PVPP_CPU0_EN";
83"FM_CPU1_VRM_OSC_EN";
84"FM_PVCCIN_PVCCSA_CPU1_EN_LVC1";
85"PWRGD_PVCCIO_CPU1";
86"FM_MEM_THERM_EVENT_PCH_N";
87"FM_FAST_PROCHOT_THROTTLE_DLY_N";
88"FM_PVDDQ_DEF_EN";
89"FM_CPU0_THERMTRIP_LVT3_N";
90"FM_PVPP_CPU1_EN";
91"FM_PLD_DEBUG_MODE_N";
92"JTAG_PLD_TCK";
93"FM_CPU1_FIVR_FAULT_LVT3_N";
94"TP_CPLD1_PT13A";
95"FM_ADR_SMI_GPIO_N";
96"PWRGD_P3V3_STBY";
97"FM_PVDDQ_ABC_EN";
98"FM_ADR_COMPLETE";
99"FM_BMC_ONCTL_N";
100"TP_CPLD1_PT11A";
101"SGPIO_BMC_DIN";
102"FM_SLPS4_N";
103"FM_PCH_PWRBTN_N";
104"PU_THERMTRIP_FORCE_N";
105"PWRGD_DSW_PWROK";
106"FM_CPU0_AND_CPU1_MCP_PRES";
107"TP_CPLD1_PT24D_DONE";
108"TP_CPLD1_PT24C_INITN";
109"TP_CPLD1_PT24B";
110"FM_SINT_PRSNT_N";
%"RES"
"1","(-1425,2675)","0","mstr_discrete","I166";
;
CDS_SEC"1"
WATTAGE"1/16W"
TOLERANCE"5.0%"
LOCATION"R2R6"
PART_NUMBER"G21497-048"
VALUE"51"
PACK_TYPE"0402"
MATERIAL"CHIP"
ROOM"CPLD"
CDS_LOCATION"R2R6"
CDS_LIB"mstr_discrete"
SEC"1"
SEC_TYPE"0402";
"B"
$PN"2"101;
"A"
$PN"1"24;
%"P3V3_STBY"
"1","(-1375,3750)","0","mstr_symbols","I171";
;
VOLTAGE"3.3V"
HDL_POWER"P3V3_STBY"
BODY_TYPE"PLUMBING"
CDS_LIB"mstr_symbols"
SIZE"1B";
"G\NAC"1;
%"RES"
"2","(-1375,3550)","2","mstr_discrete","I172";
;
CDS_SEC"1"
LOCATION"R2R7"
PART_NUMBER"G21796-072"
MATERIAL"CHIP"
PACK_TYPE"0402"
WATTAGE"1/16W"
TOLERANCE"1%"
VALUE"4.75K"
ROOM"CPLD"
CDS_LOCATION"R2R7"
BOM_COST"CPLD"
SIGNAL_MODEL"DEFAULT_RESISTOR_47000OHM_2_1"
CDS_LIB"mstr_discrete"
SEC"1"
SEC_TYPE"0402";
"A"
$PN"1"1;
"B"
$PN"2"20;
%"RES"
"1","(-3175,4325)","0","mstr_discrete","I184";
;
PACK_TYPE"0402"
VALUE"0.0"
LOCATION"R2R4"
PART_NUMBER"G21497-005"
MATERIAL"CHIP"
TOLERANCE"5%"
WATTAGE"1/16W"
ROOM"CPLD"
CDS_LOCATION"R2R4"
$SEC"1"
CDS_SEC"1"
BOM_COST"CPLD"
CDS_LIB"mstr_discrete";
"B"
$PN"2"95;
"A"
$PN"1"49;
%"RES"
"2","(-7225,2675)","0","mstr_discrete","I193";
;
CDS_SEC"1"
CDS_LOCATION"R7D42"
TOLERANCE"1%"
MATERIAL"CHIP"
PACK_TYPE"0402"
PART_NUMBER"G21796-072"
LOCATION"R7D42"
VALUE"4.75K"
WATTAGE"1/16W"
SEC_TYPE"0402"
CDS_LIB"mstr_discrete"
SEC"1"
ROOM"CPLD";
"A"
$PN"1"2;
"B"
$PN"2"41;
%"P3V3_STBY"
"1","(-7225,2900)","0","mstr_symbols","I194";
;
CDS_LIB"mstr_symbols"
SIZE"1B"
BODY_TYPE"PLUMBING"
HDL_POWER"P3V3_STBY"
VOLTAGE"3.3V";
"G\NAC"2;
%"RES"
"2","(-1700,2200)","0","mstr_discrete","I195";
;
CDS_SEC"1"
CDS_LOCATION"R4W1"
PACK_TYPE"0402"
PART_NUMBER"G21796-072"
MATERIAL"CHIP"
WATTAGE"1/16W"
TOLERANCE"1%"
VALUE"4.75K"
LOCATION"R4W1"
ROOM"CPLD"
SEC"1"
CDS_LIB"mstr_discrete"
SEC_TYPE"0402";
"A"
$PN"1"3;
"B"
$PN"2"23;
%"P3V3_STBY"
"1","(-1700,2425)","0","mstr_symbols","I196";
;
VOLTAGE"3.3V"
HDL_POWER"P3V3_STBY"
BODY_TYPE"PLUMBING"
SIZE"1B"
CDS_LIB"mstr_symbols";
"G\NAC"3;
%"RES"
"1","(-3100,1375)","0","mstr_discrete","I197";
;
WATTAGE"1/16W"
LOCATION"R1W28"
PART_NUMBER"G21497-005"
TOLERANCE"5%"
VALUE"0.0"
MATERIAL"CHIP"
SEC_TYPE"0402"
CDS_LIB"mstr_discrete"
SEC"1"
ROOM"BMC"
BOM_COST"SM_CONTROLLER"
PACK_TYPE"0402"
CDS_SEC"1"
CDS_LOCATION"R1W28";
"B"
$PN"2"103;
"A"
$PN"1"57;
%"RES"
"1","(-6200,3525)","0","mstr_discrete","I198";
;
LOCATION"R1W29"
VALUE"0.0"
TOLERANCE"5%"
PART_NUMBER"G21497-005"
WATTAGE"1/16W"
MATERIAL"CHIP"
SEC_TYPE"0402"
CDS_LIB"mstr_discrete"
SEC"1"
ROOM"BMC"
BOM_COST"SM_CONTROLLER"
PACK_TYPE"0402"
CDS_SEC"1"
CDS_LOCATION"R1W29";
"B"
$PN"2"39;
"A"
$PN"1"40;
%"LCMXO2_A"
"5","(-4475,2725)","0","mstr_memory","I59";
;
CDS_SEC"2"
LOCATION"U8D7"
PART_NUMBER"H63395-001"
MATERIAL"IC"
PACK_TYPE"256BGA"
ROOM"CPLD"
SEC_TYPE"256BGA"
SEC"2"
CDS_LIB"mstr_memory"
CDS_LMAN_SYM_OUTLINE"-550,1700,550,-1700"
CDS_LOCATION"U8D7"
BOM_COST"CPLD";
"PR1C"
$PN"C15"29;
"PR1D"
$PN"B16"9;
"PR2A"
$PN"D16"30;
"PR2B"
$PN"E14"31;
"PR2C"
$PN"C16"4;
"PR2D"
$PN"D15"32;
"PR3A"
$PN"E16"33;
"PR3B"
$PN"F15"13;
"PR3C"
$PN"F13"35;
"PR3D"
$PN"G12"34;
"PR4A"
$PN"F14"39;
"PR4B"
$PN"F16"51;
"PR4C"
$PN"F12"15;
"PR5A"
$PN"G15"12;
"PR5B"
$PN"G14"36;
"PR5C"
$PN"G11"52;
"PR5D"
$PN"H12"37;
"PR6A"
$PN"G16"10;
"PR6B"
$PN"H15"38;
"PR6C"
$PN"H13"8;
"PR6D"
$PN"J12"87;
"PR7A_PCLKT1_0"
$PN"H14"66;
"PR7B_PCLKC1_0"
$PN"H16"67;
"PR7C"
$PN"J16"68;
"PR7D"
$PN"J14"69;
"PR9A"
$PN"J15"70;
"PR9B"
$PN"K16"41;
"PR9C"
$PN"H11"71;
"PR9D"
$PN"J13"72;
"PR10A"
$PN"K14"97;
"PR10B"
$PN"K15"88;
"PR10C"
$PN"J11"73;
"PR10D"
$PN"L12"96;
"PR11A"
$PN"L16"85;
"PR11B"
$PN"L14"74;
"PR11C"
$PN"K13"62;
"PR11D"
$PN"K12"86;
"PR12A"
$PN"L15"77;
"PR12B"
$PN"M16"79;
"PR12C"
$PN"K11"78;
"PR12D"
$PN"L13"75;
"PR13A"
$PN"M14"80;
"PR13B"
$PN"M15"76;
"PR13C"
$PN"N15"89;
"PR13D"
$PN"P16"90;
"PR14A"
$PN"N16"84;
"PR14B"
$PN"N14"83;
"PR14C"
$PN"P15"82;
"PR14D"
$PN"R16"81;
"PT9A"
$PN"C4"49;
"PT9B"
$PN"B5"17;
"PT9C"
$PN"B3"18;
"PT10A"
$PN"A4"42;
"PT10B"
$PN"C5"43;
"PT11A"
$PN"A5"100;
"PT11B"
$PN"B6"44;
"PT11C"
$PN"A3"45;
"PT11D"
$PN"B4"19;
"PT12A"
$PN"D6"46;
"PT13A"
$PN"B7"94;
"PT13C"
$PN"E6"93;
"PT13D"
$PN"D7"20;
"PT16A"
$PN"F7"91;
"PT16B"
$PN"E8"63;
"PT16C_TCK"
$PN"A7"92;
"PT16D_TMS"
$PN"B8"6;
"PT17A_PCLKT0_1"
$PN"C8"98;
"PT17B_PCLKC0_1"
$PN"A8"64;
"PT17C"
$PN"D8"65;
"PT17D"
$PN"E9"21;
"PT18A"
$PN"F8"24;
"PT18B"
$PN"D9"25;
"PT18C_SCL_PCLKT0_0"
$PN"A9"26;
"PT18D_SDA_PCLKC0_0"
$PN"C9"27;
"PT19B"
$PN"A10"14;
"PT19C"
$PN"F9"22;
"PT20A"
$PN"D10"60;
"PT20B"
$PN"E10"59;
"PT21A"
$PN"A11"55;
"PT21B"
$PN"C11"54;
"PT21C"
$PN"F10"53;
"PT21D"
$PN"D11"106;
"PT22A"
$PN"B11"105;
"PT22B"
$PN"A12"104;
"PT22C"
$PN"B13"11;
"PT22D"
$PN"A14"58;
"PT23B"
$PN"B12"57;
"PT24A"
$PN"B14"110;
"PT24B"
$PN"A15"109;
"PT24C_INITN"
$PN"A13"108;
"PT24D_DONE"
$PN"C13"107;
"PT19A"
$PN"B9"5;
"PT19D"
$PN"E11"61;
"PT20C_JTAGENB"
$PN"C10"56;
"PT20D_PROGRAMN"
$PN"B10"23;
"PT23A"
$PN"C12"102;
"PR1A"
$PN"D14"28;
"PR1B"
$PN"E15"7;
"PT12B"
$PN"E7"16;
"PT12C_TDO"
$PN"C6"47;
"PT12D_TDI"
$PN"A6"48;
"PT13B"
$PN"C7"99;
"PR4D"
$PN"G13"50;
END.
